FILE_TYPE = CONNECTIVITY;
{Allegro Design Entry HDL 17.2-2016 S081 (4005846) 1/11/2022}
"PAGE_NUMBER" = 100;
0"NC";
1"M_D_CPU1_SA_CB<7:0>";
2"M_D_CPU1_SA_CA<6:0>";
3"M_D_CPU1_SB_CA<6:0>";
4"M_D_CPU1_SB_CB<7:0>";
5"M_D_CPU1_SA_DQ<31:0>";
6"M_D_CPU1_SB_DQ<31:0>";
7"M_D_CPU1_SA_DQS_DN<9:0>";
8"M_D_CPU1_SA_DQS_DP<9:0>";
9"M_D_CPU1_SB_DQS_DN<9:0>";
10"M_D_CPU1_SB_DQS_DP<9:0>";
11"GND\g";
12"GND\g";
13"P3V3_STBY\g";
14"I3C_SPD_DDRD_CPU1_SCL";
15"I3C_SPD_DDRAF_CPU1_SCL";
16"PWRGD_CHD_CPU1_DIMM";
17"I3C_SPD_DDRAF_CPU1_SDA";
18"PD_CHD_CPU1_DIMM_SAA";
19"P3V3_STBY\g";
20"TP_CHD_CPU1_DIMM_RFU_0";
21"TP_CHD_CPU1_DIMM_RFU_1";
22"TP_CHD_CPU1_DIMM_RFU_3";
23"TP_CHD_CPU1_DIMM_RFU_6";
24"PWRGD_CHAF_CPU1";
25"P12V_MEM_2\g";
26"GND\g";
27"GND\g";
28"GND\g";
29"M_D_CPU1_SB_DQS_DP<9>";
30"M_D_CPU1_SB_DQS_DN<9>";
31"M_D_CPU1_SA_DQS_DP<9>";
32"M_D_CPU1_SA_DQS_DN<9>";
33"M_D_CPU1_SA_DQS_DP<8>";
34"M_D_CPU1_SA_DQS_DN<8>";
35"M_D_CPU1_SB_DQS_DN<7>";
36"M_D_CPU1_SA_DQS_DP<7>";
37"M_D_CPU1_SB_DQS_DP<6>";
38"M_D_CPU1_SB_DQS_DN<6>";
39"M_D_CPU1_SA_DQS_DN<6>";
40"M_D_CPU1_SB_DQS_DP<5>";
41"M_D_CPU1_SB_DQS_DN<5>";
42"M_D_CPU1_SA_DQS_DP<5>";
43"M_D_CPU1_SA_DQS_DN<5>";
44"M_D_CPU1_SB_DQS_DP<4>";
45"M_D_CPU1_SB_DQS_DN<4>";
46"M_D_CPU1_SA_DQS_DP<4>";
47"M_D_CPU1_SA_DQS_DN<4>";
48"M_D_CPU1_SB_DQS_DP<3>";
49"M_D_CPU1_SB_DQS_DN<3>";
50"M_D_CPU1_SA_DQS_DP<3>";
51"M_D_CPU1_SA_DQS_DN<3>";
52"M_D_CPU1_SB_DQS_DP<2>";
53"M_D_CPU1_SB_DQS_DN<2>";
54"M_D_CPU1_SA_DQS_DP<2>";
55"M_D_CPU1_SA_DQS_DN<2>";
56"M_D_CPU1_SB_DQS_DP<1>";
57"M_D_CPU1_SB_DQS_DN<1>";
58"M_D_CPU1_SA_DQS_DP<1>";
59"M_D_CPU1_SA_DQS_DN<1>";
60"M_D_CPU1_SB_DQS_DP<0>";
61"M_D_CPU1_SB_DQS_DN<0>";
62"M_D_CPU1_SA_DQS_DP<0>";
63"M_D_CPU1_SA_DQS_DN<0>";
64"M_D_CPU1_SB_DQS_DP<7>";
65"M_D_CPU1_SB_DQS_DN<8>";
66"M_D_CPU1_SB_DQS_DP<8>";
67"M_D_CPU1_SA_DQS_DP<6>";
68"M_D_CPU1_SA_DQS_DN<7>";
69"M_D_CPU1_SA_DQ<31>";
70"TP_CHD_CPU1_DIMM_RFU_2";
71"TP_CHD_CPU1_DIMM_RFU_4";
72"TP_CHD_CPU1_DIMM_RFU_5";
73"M_D_CPU1_RESET_N";
74"M_D_CPU1_SB_PAR";
75"M_D_CPU1_SA_PAR";
76"M_D_CPU1_SB_RSP<0>";
77"M_D_CPU1_SA_RSP<0>";
78"M_D_CPU1_SB_DQ<0>";
79"M_D_CPU1_SB_DQ<1>";
80"M_D_CPU1_SB_DQ<2>";
81"M_D_CPU1_SB_DQ<3>";
82"M_D_CPU1_SB_DQ<4>";
83"M_D_CPU1_SB_DQ<5>";
84"M_D_CPU1_SB_DQ<6>";
85"M_D_CPU1_SB_DQ<7>";
86"M_D_CPU1_SB_DQ<8>";
87"M_D_CPU1_SB_DQ<9>";
88"M_D_CPU1_SB_DQ<10>";
89"M_D_CPU1_SB_DQ<11>";
90"M_D_CPU1_SB_DQ<12>";
91"M_D_CPU1_SB_DQ<13>";
92"M_D_CPU1_SB_DQ<14>";
93"M_D_CPU1_SB_DQ<15>";
94"M_D_CPU1_SB_DQ<16>";
95"M_D_CPU1_SB_DQ<17>";
96"M_D_CPU1_SB_DQ<18>";
97"M_D_CPU1_SB_DQ<19>";
98"M_D_CPU1_SB_DQ<20>";
99"M_D_CPU1_SB_DQ<21>";
100"M_D_CPU1_SB_DQ<22>";
101"M_D_CPU1_SB_DQ<23>";
102"M_D_CPU1_SB_DQ<24>";
103"M_D_CPU1_SB_DQ<25>";
104"M_D_CPU1_SB_DQ<26>";
105"M_D_CPU1_SB_DQ<27>";
106"M_D_CPU1_SB_DQ<28>";
107"M_D_CPU1_SB_DQ<29>";
108"M_D_CPU1_SB_DQ<30>";
109"M_D_CPU1_SB_DQ<31>";
110"M_D_CPU1_SA_DQ<0>";
111"M_D_CPU1_SA_DQ<1>";
112"M_D_CPU1_SA_DQ<2>";
113"M_D_CPU1_SA_DQ<3>";
114"M_D_CPU1_SA_DQ<4>";
115"M_D_CPU1_SA_DQ<5>";
116"M_D_CPU1_SA_DQ<6>";
117"M_D_CPU1_SA_DQ<7>";
118"M_D_CPU1_SA_DQ<8>";
119"M_D_CPU1_SA_DQ<9>";
120"M_D_CPU1_SA_DQ<10>";
121"M_D_CPU1_SA_DQ<11>";
122"M_D_CPU1_SA_DQ<12>";
123"M_D_CPU1_SA_DQ<13>";
124"M_D_CPU1_SA_DQ<14>";
125"M_D_CPU1_SA_DQ<15>";
126"M_D_CPU1_SA_DQ<16>";
127"M_D_CPU1_SA_DQ<17>";
128"M_D_CPU1_SA_DQ<18>";
129"M_D_CPU1_SA_DQ<19>";
130"M_D_CPU1_SA_DQ<20>";
131"M_D_CPU1_SA_DQ<21>";
132"M_D_CPU1_SA_DQ<22>";
133"M_D_CPU1_SA_DQ<23>";
134"M_D_CPU1_SA_DQ<24>";
135"M_D_CPU1_SA_DQ<25>";
136"M_D_CPU1_SA_DQ<26>";
137"M_D_CPU1_SA_DQ<27>";
138"M_D_CPU1_SA_DQ<28>";
139"M_D_CPU1_SA_DQ<29>";
140"M_D_CPU1_SA_DQ<30>";
141"M_D_CPU1_SB_CS_N<1>";
142"M_D_CPU1_SA_CS_N<1>";
143"M_D_CPU1_SB_CS_N<0>";
144"M_D_CPU1_SA_CS_N<0>";
145"M_D_CPU1_CLK_DP<0>";
146"M_D_CPU1_CLK_DN<0>";
147"M_D_CPU1_SB_CB<0>";
148"M_D_CPU1_SB_CB<1>";
149"M_D_CPU1_SB_CB<2>";
150"M_D_CPU1_SB_CB<3>";
151"M_D_CPU1_SB_CB<4>";
152"M_D_CPU1_SB_CB<5>";
153"M_D_CPU1_SB_CB<6>";
154"M_D_CPU1_SA_CB<0>";
155"M_D_CPU1_SA_CB<2>";
156"M_D_CPU1_SA_CB<3>";
157"M_D_CPU1_SA_CB<5>";
158"M_D_CPU1_SA_CB<6>";
159"M_D_CPU1_SB_CA<6>";
160"M_D_CPU1_SA_CA<6>";
161"M_D_CPU1_SB_CA<5>";
162"M_D_CPU1_SA_CA<5>";
163"M_D_CPU1_SB_CA<4>";
164"M_D_CPU1_SA_CA<4>";
165"M_D_CPU1_SB_CA<3>";
166"M_D_CPU1_SA_CA<3>";
167"M_D_CPU1_SB_CA<2>";
168"M_D_CPU1_SA_CA<2>";
169"M_D_CPU1_SB_CA<1>";
170"M_D_CPU1_SA_CA<1>";
171"M_D_CPU1_SB_CA<0>";
172"M_D_CPU1_SA_CA<0>";
173"M_D_CPU1_ALERT_N";
174"M_D_CPU1_SB_CB<7>";
175"M_D_CPU1_SA_CB<1>";
176"M_D_CPU1_SA_CB<4>";
177"M_D_CPU1_SA_CB<7>";
178"PD_CHD_CPU1_DIMM_SAA";
%"TAP"
"1","(-6100,4225)","0","mstr_standard","I107";
;
CDS_LIB"mstr_standard"
BODY_TYPE"PLUMBING"
HDL_TAP"TRUE";
"B \NAC \NWC"5;
"S \NAC"
BN"4"114;
%"TAP"
"1","(-6100,4275)","0","mstr_standard","I108";
;
CDS_LIB"mstr_standard"
BODY_TYPE"PLUMBING"
HDL_TAP"TRUE";
"B \NAC \NWC"5;
"S \NAC"
BN"5"115;
%"TAP"
"1","(-6100,4325)","0","mstr_standard","I109";
;
CDS_LIB"mstr_standard"
BODY_TYPE"PLUMBING"
HDL_TAP"TRUE";
"B \NAC \NWC"5;
"S \NAC"
BN"6"116;
%"TAP"
"1","(-6100,4375)","0","mstr_standard","I110";
;
CDS_LIB"mstr_standard"
BODY_TYPE"PLUMBING"
HDL_TAP"TRUE";
"B \NAC \NWC"5;
"S \NAC"
BN"7"117;
%"TAP"
"1","(-6100,4425)","0","mstr_standard","I111";
;
CDS_LIB"mstr_standard"
BODY_TYPE"PLUMBING"
HDL_TAP"TRUE";
"B \NAC \NWC"5;
"S \NAC"
BN"8"118;
%"TAP"
"1","(-6100,4475)","0","mstr_standard","I112";
;
CDS_LIB"mstr_standard"
BODY_TYPE"PLUMBING"
HDL_TAP"TRUE";
"B \NAC \NWC"5;
"S \NAC"
BN"9"119;
%"TAP"
"1","(-6100,4575)","0","mstr_standard","I113";
;
CDS_LIB"mstr_standard"
BODY_TYPE"PLUMBING"
HDL_TAP"TRUE";
"B \NAC \NWC"5;
"S \NAC"
BN"11"121;
%"TAP"
"1","(-6100,4525)","0","mstr_standard","I114";
;
CDS_LIB"mstr_standard"
BODY_TYPE"PLUMBING"
HDL_TAP"TRUE";
"B \NAC \NWC"5;
"S \NAC"
BN"10"120;
%"TAP"
"1","(-6100,4625)","0","mstr_standard","I115";
;
CDS_LIB"mstr_standard"
BODY_TYPE"PLUMBING"
HDL_TAP"TRUE";
"B \NAC \NWC"5;
"S \NAC"
BN"12"122;
%"TAP"
"1","(-6100,4675)","0","mstr_standard","I116";
;
CDS_LIB"mstr_standard"
BODY_TYPE"PLUMBING"
HDL_TAP"TRUE";
"B \NAC \NWC"5;
"S \NAC"
BN"13"123;
%"TAP"
"1","(-6100,4725)","0","mstr_standard","I117";
;
CDS_LIB"mstr_standard"
BODY_TYPE"PLUMBING"
HDL_TAP"TRUE";
"B \NAC \NWC"5;
"S \NAC"
BN"14"124;
%"TAP"
"1","(-6100,4825)","0","mstr_standard","I118";
;
CDS_LIB"mstr_standard"
BODY_TYPE"PLUMBING"
HDL_TAP"TRUE";
"B \NAC \NWC"5;
"S \NAC"
BN"16"126;
%"TAP"
"1","(-6100,4775)","0","mstr_standard","I119";
;
CDS_LIB"mstr_standard"
BODY_TYPE"PLUMBING"
HDL_TAP"TRUE";
"B \NAC \NWC"5;
"S \NAC"
BN"15"125;
%"TAP"
"1","(-7800,3425)","2","mstr_standard","I12";
;
CDS_LIB"mstr_standard"
BODY_TYPE"PLUMBING"
HDL_TAP"TRUE";
"B \NAC \NWC"4;
"S \NAC"
BN"1"148;
%"TAP"
"1","(-6100,4875)","0","mstr_standard","I120";
;
CDS_LIB"mstr_standard"
BODY_TYPE"PLUMBING"
HDL_TAP"TRUE";
"B \NAC \NWC"5;
"S \NAC"
BN"17"127;
%"TAP"
"1","(-6100,4925)","0","mstr_standard","I121";
;
CDS_LIB"mstr_standard"
BODY_TYPE"PLUMBING"
HDL_TAP"TRUE";
"B \NAC \NWC"5;
"S \NAC"
BN"18"128;
%"TAP"
"1","(-6100,5025)","0","mstr_standard","I122";
;
CDS_LIB"mstr_standard"
BODY_TYPE"PLUMBING"
HDL_TAP"TRUE";
"B \NAC \NWC"5;
"S \NAC"
BN"20"130;
%"TAP"
"1","(-6100,4975)","0","mstr_standard","I123";
;
CDS_LIB"mstr_standard"
BODY_TYPE"PLUMBING"
HDL_TAP"TRUE";
"B \NAC \NWC"5;
"S \NAC"
BN"19"129;
%"TAP"
"1","(-6100,5075)","0","mstr_standard","I124";
;
CDS_LIB"mstr_standard"
BODY_TYPE"PLUMBING"
HDL_TAP"TRUE";
"B \NAC \NWC"5;
"S \NAC"
BN"21"131;
%"TAP"
"1","(-6100,5125)","0","mstr_standard","I125";
;
CDS_LIB"mstr_standard"
BODY_TYPE"PLUMBING"
HDL_TAP"TRUE";
"B \NAC \NWC"5;
"S \NAC"
BN"22"132;
%"TAP"
"1","(-6100,5175)","0","mstr_standard","I126";
;
CDS_LIB"mstr_standard"
BODY_TYPE"PLUMBING"
HDL_TAP"TRUE";
"B \NAC \NWC"5;
"S \NAC"
BN"23"133;
%"TAP"
"1","(-6100,5275)","0","mstr_standard","I127";
;
CDS_LIB"mstr_standard"
BODY_TYPE"PLUMBING"
HDL_TAP"TRUE";
"B \NAC \NWC"5;
"S \NAC"
BN"25"135;
%"TAP"
"1","(-6100,5225)","0","mstr_standard","I128";
;
CDS_LIB"mstr_standard"
BODY_TYPE"PLUMBING"
HDL_TAP"TRUE";
"B \NAC \NWC"5;
"S \NAC"
BN"24"134;
%"TAP"
"1","(-6100,5325)","0","mstr_standard","I129";
;
CDS_LIB"mstr_standard"
BODY_TYPE"PLUMBING"
HDL_TAP"TRUE";
"B \NAC \NWC"5;
"S \NAC"
BN"26"136;
%"TAP"
"1","(-7800,3375)","2","mstr_standard","I13";
;
CDS_LIB"mstr_standard"
BODY_TYPE"PLUMBING"
HDL_TAP"TRUE";
"B \NAC \NWC"4;
"S \NAC"
BN"0"147;
%"TAP"
"1","(-6100,5375)","0","mstr_standard","I130";
;
CDS_LIB"mstr_standard"
BODY_TYPE"PLUMBING"
HDL_TAP"TRUE";
"B \NAC \NWC"5;
"S \NAC"
BN"27"137;
%"TAP"
"1","(-6100,5475)","0","mstr_standard","I131";
;
CDS_LIB"mstr_standard"
BODY_TYPE"PLUMBING"
HDL_TAP"TRUE";
"B \NAC \NWC"5;
"S \NAC"
BN"29"139;
%"TAP"
"1","(-6100,5425)","0","mstr_standard","I132";
;
CDS_LIB"mstr_standard"
BODY_TYPE"PLUMBING"
HDL_TAP"TRUE";
"B \NAC \NWC"5;
"S \NAC"
BN"28"138;
%"TAP"
"1","(-6100,5525)","0","mstr_standard","I133";
;
CDS_LIB"mstr_standard"
BODY_TYPE"PLUMBING"
HDL_TAP"TRUE";
"B \NAC \NWC"5;
"S \NAC"
BN"30"140;
%"TAP"
"1","(-6100,5575)","0","mstr_standard","I134";
;
CDS_LIB"mstr_standard"
BODY_TYPE"PLUMBING"
HDL_TAP"TRUE";
"B \NAC \NWC"5;
"S \NAC"
BN"31"69;
%"TAP"
"1","(-7800,3525)","2","mstr_standard","I14";
;
CDS_LIB"mstr_standard"
BODY_TYPE"PLUMBING"
HDL_TAP"TRUE";
"B \NAC \NWC"4;
"S \NAC"
BN"3"150;
%"GND"
"1","(-6525,1200)","0","mstr_symbols","I145";
;
SIZE"1B"
BOM_COST"MEM"
CDS_LIB"mstr_symbols"
BODY_TYPE"PLUMBING"
VOLTAGE"0.0"
HDL_POWER"GND";
"A\NAC"11;
%"Q_RES"
"2","(-6525,1425)","0","pure_quanta","I146";
;
LOCATION"R772"
$SEC"1"
CDS_SEC"1"
WATTAGE"1/16W"
MATERIAL"CHIP"
TOLERANCE"1%"
VALUE"35.7K"
PART_NUMBER"CS33572FB01"
PACK_TYPE"0402LF"
CDS_LIB"pure_quanta";
"A"
$PN"1"178;
"B"
$PN"2"11;
%"GND"
"1","(-2200,2000)","0","mstr_symbols","I147";
;
CDS_LIB"mstr_symbols"
SIZE"1B"
BODY_TYPE"PLUMBING"
VOLTAGE"0.0"
HDL_POWER"GND";
"A\NAC"28;
%"TAP"
"1","(-7800,3475)","2","mstr_standard","I15";
;
CDS_LIB"mstr_standard"
BODY_TYPE"PLUMBING"
HDL_TAP"TRUE";
"B \NAC \NWC"4;
"S \NAC"
BN"2"149;
%"TAP"
"1","(-7800,3625)","2","mstr_standard","I16";
;
CDS_LIB"mstr_standard"
BODY_TYPE"PLUMBING"
HDL_TAP"TRUE";
"B \NAC \NWC"4;
"S \NAC"
BN"5"152;
%"SCONN288_DDR506112002KQ"
"3","(-1300,3750)","0","pure_quanta","I161";
;
LOCATION"J30"
$SEC"3"
CDS_SEC"3"
PART_TYPE"SMLF"
MATERIAL"IO"
VALUE"SCONN288_DDR506112002KQ"
PART_NUMBER"DFHST8FS479"
CDS_LMAN_SYM_OUTLINE"-450,1800,450,-1750"
NEEDS_NO_SIZE"TRUE"
CDS_LIB"pure_quanta";
"G3"
$PN"G3"27;
"G2"
$PN"G2"27;
"G1"
$PN"G1"27;
"VSS62"
$PN"141"27;
"VSS61"
$PN"139"27;
"VSS60"
$PN"136"27;
"VSS58"
$PN"132"27;
"VSS104"
$PN"240"28;
"VSS102"
$PN"235"28;
"VSS100"
$PN"230"28;
"VIN_BULK2"
$PN"146"25;
"VIN_BULK1"
$PN"145"25;
"VIN_BULK0"
$PN"1"25;
"VSS126"
$PN"288"28;
"VSS125"
$PN"286"28;
"VSS124"
$PN"284"28;
"VSS123"
$PN"281"28;
"VSS122"
$PN"279"28;
"VSS121"
$PN"277"28;
"VSS120"
$PN"275"28;
"VSS119"
$PN"273"28;
"VSS118"
$PN"270"28;
"VSS117"
$PN"268"28;
"VSS116"
$PN"266"28;
"VSS115"
$PN"264"28;
"VSS114"
$PN"262"28;
"VSS113"
$PN"259"28;
"VSS112"
$PN"257"28;
"VSS111"
$PN"255"28;
"VSS110"
$PN"253"28;
"VSS109"
$PN"251"28;
"VSS108"
$PN"248"28;
"VSS107"
$PN"246"28;
"VSS106"
$PN"244"28;
"VSS105"
$PN"242"28;
"VSS103"
$PN"237"28;
"VSS101"
$PN"233"28;
"VSS99"
$PN"228"28;
"VSS98"
$PN"226"28;
"VSS97"
$PN"224"28;
"VSS96"
$PN"222"28;
"VSS95"
$PN"219"28;
"VSS94"
$PN"216"28;
"VSS93"
$PN"214"28;
"VSS92"
$PN"212"28;
"VSS91"
$PN"210"28;
"VSS90"
$PN"208"28;
"VSS89"
$PN"206"28;
"VSS88"
$PN"204"28;
"VSS87"
$PN"202"28;
"VSS86"
$PN"199"28;
"VSS85"
$PN"197"28;
"VSS84"
$PN"195"28;
"VSS83"
$PN"193"28;
"VSS82"
$PN"191"28;
"VSS81"
$PN"188"28;
"VSS80"
$PN"186"28;
"VSS79"
$PN"184"28;
"VSS78"
$PN"182"28;
"VSS77"
$PN"180"28;
"VSS76"
$PN"177"28;
"VSS75"
$PN"175"28;
"VSS74"
$PN"173"28;
"VSS73"
$PN"171"28;
"VSS72"
$PN"169"28;
"VSS71"
$PN"166"28;
"VSS70"
$PN"164"28;
"VSS69"
$PN"162"28;
"VSS68"
$PN"160"28;
"VSS67"
$PN"158"28;
"VSS66"
$PN"155"28;
"VSS65"
$PN"153"28;
"VSS64"
$PN"151"28;
"VSS63"
$PN"143"27;
"VSS59"
$PN"134"27;
"VSS57"
$PN"130"27;
"VSS56"
$PN"128"27;
"VSS55"
$PN"125"27;
"VSS54"
$PN"123"27;
"VSS53"
$PN"121"27;
"VSS52"
$PN"119"27;
"VSS51"
$PN"117"27;
"VSS50"
$PN"114"27;
"VSS49"
$PN"112"27;
"VSS48"
$PN"110"27;
"VSS47"
$PN"108"27;
"VSS46"
$PN"106"27;
"VSS45"
$PN"103"27;
"VSS44"
$PN"101"27;
"VSS43"
$PN"99"27;
"VSS42"
$PN"97"27;
"VSS41"
$PN"95"27;
"VSS40"
$PN"92"27;
"VSS39"
$PN"90"27;
"VSS38"
$PN"88"27;
"VSS37"
$PN"85"27;
"VSS36"
$PN"83"27;
"VSS35"
$PN"81"27;
"VSS34"
$PN"79"27;
"VSS33"
$PN"77"27;
"VSS32"
$PN"75"27;
"VSS31"
$PN"73"27;
"VSS30"
$PN"71"27;
"VSS29"
$PN"69"27;
"VSS28"
$PN"67"27;
"VSS27"
$PN"65"27;
"VSS26"
$PN"63"27;
"VSS25"
$PN"61"27;
"VSS24"
$PN"59"27;
"VSS23"
$PN"57"27;
"VSS22"
$PN"54"27;
"VSS21"
$PN"52"27;
"VSS20"
$PN"50"27;
"VSS19"
$PN"48"27;
"VSS18"
$PN"46"27;
"VSS17"
$PN"43"27;
"VSS16"
$PN"41"27;
"VSS15"
$PN"39"27;
"VSS14"
$PN"37"27;
"VSS13"
$PN"35"27;
"VSS12"
$PN"32"27;
"VSS11"
$PN"30"27;
"VSS10"
$PN"28"27;
"VSS9"
$PN"26"27;
"VSS8"
$PN"24"27;
"VSS7"
$PN"21"27;
"VSS6"
$PN"19"27;
"VSS5"
$PN"17"27;
"VSS4"
$PN"15"27;
"VSS3"
$PN"13"27;
"VSS2"
$PN"10"27;
"VSS1"
$PN"8"27;
"VSS0"
$PN"6"27;
%"GND"
"1","(-400,1800)","0","mstr_symbols","I162";
;
SIZE"1B"
CDS_LIB"mstr_symbols"
BODY_TYPE"PLUMBING"
VOLTAGE"0.0"
HDL_POWER"GND";
"A\NAC"27;
%"TAP"
"1","(-7800,3575)","2","mstr_standard","I17";
;
CDS_LIB"mstr_standard"
BODY_TYPE"PLUMBING"
HDL_TAP"TRUE";
"B \NAC \NWC"4;
"S \NAC"
BN"4"151;
%"TAP"
"1","(-7800,3675)","2","mstr_standard","I18";
;
CDS_LIB"mstr_standard"
BODY_TYPE"PLUMBING"
HDL_TAP"TRUE";
"B \NAC \NWC"4;
"S \NAC"
BN"6"153;
%"Q_CAP"
"1","(-8750,3400)","2","pure_quanta","I185";
;
LOCATION"C148"
$SEC"1"
CDS_SEC"1"
MATERIAL"X7R"
TOLERANCE"10%"
VALUE"0.1UF"
PART_NUMBER"CH4104K1B00"
VOLTAGE"25V"
PACK_TYPE"0402"
CDS_LIB"pure_quanta"
BOM_COST"MEM"
ROOM"MEM_CH_A_CPU0_DIMM1";
"B"
$PN"2"12;
"A"
$PN"1"19;
%"GND"
"1","(-8750,3175)","0","mstr_symbols","I186";
;
CDS_LIB"mstr_symbols"
SIZE"1B"
BOM_COST"MEM"
BODY_TYPE"PLUMBING"
VOLTAGE"0"
ROOM"MEM_EFGH_DECOUPLING_CAPS"
HDL_POWER"GND";
"A\NAC"12;
%"Q_RES"
"1","(-8600,2325)","2","pure_quanta","I188";
;
LOCATION"R306"
$SEC"1"
CDS_SEC"1"
VALUE"0"
CDS_LIB"pure_quanta"
BOM_COST"MEM"
WATTAGE"1/16W"
MATERIAL"CHIP"
TOLERANCE"5%"
PART_NUMBER"CS00002JB38"
PACK_TYPE"0402LF"
ROOM"RST_CPU0_PLD_TO_DIMM";
"B"
$PN"2"24;
"A"
$PN"1"16;
%"VCC_CORE"
"1","(-8475,2650)","0","mstr_symbols","I189";
;
HDL_POWER"P3V3_STBY"
CDS_LIB"mstr_symbols"
VOLTAGE"3.3"
ROOM"PVCCINFAON_CPU0_CTRL";
"A"13;
%"TAP"
"1","(-7800,3875)","2","mstr_standard","I19";
;
CDS_LIB"mstr_standard"
BODY_TYPE"PLUMBING"
HDL_TAP"TRUE";
"B \NAC \NWC"1;
"S \NAC"
BN"1"175;
%"Q_RES"
"2","(-8475,2475)","0","pure_quanta","I190";
;
LOCATION"R106"
$SEC"1"
CDS_SEC"1"
TOLERANCE"5%"
VALUE"1K"
PACK_TYPE"0402LF"
MATERIAL"EMPTY"
WATTAGE"1/16W"
BOM_COST"MEM"
CDS_LIB"pure_quanta"
PART_NUMBER"TMP_QCS21002JB34"
ROOM"MEM_CH_A_CPU0_DIMM1";
"A"
$PN"1"13;
"B"
$PN"2"16;
%"TAP"
"1","(-3275,3875)","0","mstr_standard","I191";
;
CDS_LIB"mstr_standard"
BODY_TYPE"PLUMBING"
HDL_TAP"TRUE";
"B \NAC \NWC"7;
"S \NAC"
BN"1"59;
%"TAP"
"1","(-3275,3975)","0","mstr_standard","I192";
;
CDS_LIB"mstr_standard"
BODY_TYPE"PLUMBING"
HDL_TAP"TRUE";
"B \NAC \NWC"7;
"S \NAC"
BN"2"55;
%"TAP"
"1","(-3475,4025)","0","mstr_standard","I193";
;
CDS_LIB"mstr_standard"
BODY_TYPE"PLUMBING"
HDL_TAP"TRUE";
"B \NAC \NWC"8;
"S \NAC"
BN"2"54;
%"TAP"
"1","(-3475,4125)","0","mstr_standard","I194";
;
CDS_LIB"mstr_standard"
BODY_TYPE"PLUMBING"
HDL_TAP"TRUE";
"B \NAC \NWC"8;
"S \NAC"
BN"3"50;
%"TAP"
"1","(-3275,4675)","0","mstr_standard","I198";
;
CDS_LIB"mstr_standard"
BODY_TYPE"PLUMBING"
HDL_TAP"TRUE";
"B \NAC \NWC"7;
"S \NAC"
BN"9"32;
%"TAP"
"1","(-3275,4575)","0","mstr_standard","I199";
;
CDS_LIB"mstr_standard"
BODY_TYPE"PLUMBING"
HDL_TAP"TRUE";
"B \NAC \NWC"7;
"S \NAC"
BN"8"34;
%"TAP"
"1","(-7800,3825)","2","mstr_standard","I20";
;
CDS_LIB"mstr_standard"
BODY_TYPE"PLUMBING"
HDL_TAP"TRUE";
"B \NAC \NWC"1;
"S \NAC"
BN"0"154;
%"TAP"
"1","(-3275,4475)","0","mstr_standard","I200";
;
CDS_LIB"mstr_standard"
BODY_TYPE"PLUMBING"
HDL_TAP"TRUE";
"B \NAC \NWC"7;
"S \NAC"
BN"7"68;
%"TAP"
"1","(-3275,4375)","0","mstr_standard","I201";
;
CDS_LIB"mstr_standard"
BODY_TYPE"PLUMBING"
HDL_TAP"TRUE";
"B \NAC \NWC"7;
"S \NAC"
BN"6"39;
%"TAP"
"1","(-3475,4625)","0","mstr_standard","I202";
;
CDS_LIB"mstr_standard"
BODY_TYPE"PLUMBING"
HDL_TAP"TRUE";
"B \NAC \NWC"8;
"S \NAC"
BN"8"33;
%"TAP"
"1","(-3475,4725)","0","mstr_standard","I203";
;
CDS_LIB"mstr_standard"
BODY_TYPE"PLUMBING"
HDL_TAP"TRUE";
"B \NAC \NWC"8;
"S \NAC"
BN"9"31;
%"TAP"
"1","(-3475,4425)","0","mstr_standard","I204";
;
CDS_LIB"mstr_standard"
BODY_TYPE"PLUMBING"
HDL_TAP"TRUE";
"B \NAC \NWC"8;
"S \NAC"
BN"6"67;
%"TAP"
"1","(-3475,4525)","0","mstr_standard","I205";
;
CDS_LIB"mstr_standard"
BODY_TYPE"PLUMBING"
HDL_TAP"TRUE";
"B \NAC \NWC"8;
"S \NAC"
BN"7"36;
%"TAP"
"1","(-3475,4325)","0","mstr_standard","I206";
;
CDS_LIB"mstr_standard"
BODY_TYPE"PLUMBING"
HDL_TAP"TRUE";
"B \NAC \NWC"8;
"S \NAC"
BN"5"42;
%"TAP"
"1","(-3275,4275)","0","mstr_standard","I207";
;
CDS_LIB"mstr_standard"
BODY_TYPE"PLUMBING"
HDL_TAP"TRUE";
"B \NAC \NWC"7;
"S \NAC"
BN"5"43;
%"TAP"
"1","(-3275,4175)","0","mstr_standard","I208";
;
CDS_LIB"mstr_standard"
BODY_TYPE"PLUMBING"
HDL_TAP"TRUE";
"B \NAC \NWC"7;
"S \NAC"
BN"4"47;
%"TAP"
"1","(-3275,4075)","0","mstr_standard","I209";
;
CDS_LIB"mstr_standard"
BODY_TYPE"PLUMBING"
HDL_TAP"TRUE";
"B \NAC \NWC"7;
"S \NAC"
BN"3"51;
%"TAP"
"1","(-7800,3725)","2","mstr_standard","I21";
;
CDS_LIB"mstr_standard"
BODY_TYPE"PLUMBING"
HDL_TAP"TRUE";
"B \NAC \NWC"4;
"S \NAC"
BN"7"174;
%"TAP"
"1","(-3475,4225)","0","mstr_standard","I210";
;
CDS_LIB"mstr_standard"
BODY_TYPE"PLUMBING"
HDL_TAP"TRUE";
"B \NAC \NWC"8;
"S \NAC"
BN"4"46;
%"TAP"
"1","(-3475,3925)","0","mstr_standard","I211";
;
CDS_LIB"mstr_standard"
BODY_TYPE"PLUMBING"
HDL_TAP"TRUE";
"B \NAC \NWC"8;
"S \NAC"
BN"1"58;
%"TAP"
"1","(-3475,3825)","0","mstr_standard","I212";
;
CDS_LIB"mstr_standard"
BODY_TYPE"PLUMBING"
HDL_TAP"TRUE";
"B \NAC \NWC"8;
"S \NAC"
BN"0"62;
%"TAP"
"1","(-3275,3625)","0","mstr_standard","I215";
;
CDS_LIB"mstr_standard"
BODY_TYPE"PLUMBING"
HDL_TAP"TRUE";
"B \NAC \NWC"9;
"S \NAC"
BN"9"30;
%"TAP"
"1","(-3275,3775)","0","mstr_standard","I216";
;
CDS_LIB"mstr_standard"
BODY_TYPE"PLUMBING"
HDL_TAP"TRUE";
"B \NAC \NWC"7;
"S \NAC"
BN"0"63;
%"TAP"
"1","(-3275,3525)","0","mstr_standard","I217";
;
CDS_LIB"mstr_standard"
BODY_TYPE"PLUMBING"
HDL_TAP"TRUE";
"B \NAC \NWC"9;
"S \NAC"
BN"8"65;
%"TAP"
"1","(-3275,3425)","0","mstr_standard","I218";
;
CDS_LIB"mstr_standard"
BODY_TYPE"PLUMBING"
HDL_TAP"TRUE";
"B \NAC \NWC"9;
"S \NAC"
BN"7"35;
%"TAP"
"1","(-3275,3325)","0","mstr_standard","I219";
;
CDS_LIB"mstr_standard"
BODY_TYPE"PLUMBING"
HDL_TAP"TRUE";
"B \NAC \NWC"9;
"S \NAC"
BN"6"38;
%"TAP"
"1","(-7800,3925)","2","mstr_standard","I22";
;
CDS_LIB"mstr_standard"
BODY_TYPE"PLUMBING"
HDL_TAP"TRUE";
"B \NAC \NWC"1;
"S \NAC"
BN"2"155;
%"TAP"
"1","(-3475,3575)","0","mstr_standard","I220";
;
CDS_LIB"mstr_standard"
BODY_TYPE"PLUMBING"
HDL_TAP"TRUE";
"B \NAC \NWC"10;
"S \NAC"
BN"8"66;
%"TAP"
"1","(-3475,3675)","0","mstr_standard","I221";
;
CDS_LIB"mstr_standard"
BODY_TYPE"PLUMBING"
HDL_TAP"TRUE";
"B \NAC \NWC"10;
"S \NAC"
BN"9"29;
%"TAP"
"1","(-3475,3375)","0","mstr_standard","I222";
;
CDS_LIB"mstr_standard"
BODY_TYPE"PLUMBING"
HDL_TAP"TRUE";
"B \NAC \NWC"10;
"S \NAC"
BN"6"37;
%"TAP"
"1","(-3475,3475)","0","mstr_standard","I223";
;
CDS_LIB"mstr_standard"
BODY_TYPE"PLUMBING"
HDL_TAP"TRUE";
"B \NAC \NWC"10;
"S \NAC"
BN"7"64;
%"TAP"
"1","(-3275,3225)","0","mstr_standard","I224";
;
CDS_LIB"mstr_standard"
BODY_TYPE"PLUMBING"
HDL_TAP"TRUE";
"B \NAC \NWC"9;
"S \NAC"
BN"5"41;
%"TAP"
"1","(-3275,3125)","0","mstr_standard","I225";
;
CDS_LIB"mstr_standard"
BODY_TYPE"PLUMBING"
HDL_TAP"TRUE";
"B \NAC \NWC"9;
"S \NAC"
BN"4"45;
%"TAP"
"1","(-3275,3025)","0","mstr_standard","I226";
;
CDS_LIB"mstr_standard"
BODY_TYPE"PLUMBING"
HDL_TAP"TRUE";
"B \NAC \NWC"9;
"S \NAC"
BN"3"49;
%"TAP"
"1","(-3275,2925)","0","mstr_standard","I227";
;
CDS_LIB"mstr_standard"
BODY_TYPE"PLUMBING"
HDL_TAP"TRUE";
"B \NAC \NWC"9;
"S \NAC"
BN"2"53;
%"TAP"
"1","(-3275,2825)","0","mstr_standard","I228";
;
CDS_LIB"mstr_standard"
BODY_TYPE"PLUMBING"
HDL_TAP"TRUE";
"B \NAC \NWC"9;
"S \NAC"
BN"1"57;
%"TAP"
"1","(-3475,3075)","0","mstr_standard","I229";
;
CDS_LIB"mstr_standard"
BODY_TYPE"PLUMBING"
HDL_TAP"TRUE";
"B \NAC \NWC"10;
"S \NAC"
BN"3"48;
%"TAP"
"1","(-7800,3975)","2","mstr_standard","I23";
;
CDS_LIB"mstr_standard"
BODY_TYPE"PLUMBING"
HDL_TAP"TRUE";
"B \NAC \NWC"1;
"S \NAC"
BN"3"156;
%"TAP"
"1","(-3475,3275)","0","mstr_standard","I230";
;
CDS_LIB"mstr_standard"
BODY_TYPE"PLUMBING"
HDL_TAP"TRUE";
"B \NAC \NWC"10;
"S \NAC"
BN"5"40;
%"TAP"
"1","(-3475,3175)","0","mstr_standard","I231";
;
CDS_LIB"mstr_standard"
BODY_TYPE"PLUMBING"
HDL_TAP"TRUE";
"B \NAC \NWC"10;
"S \NAC"
BN"4"44;
%"TAP"
"1","(-3475,2775)","0","mstr_standard","I232";
;
CDS_LIB"mstr_standard"
BODY_TYPE"PLUMBING"
HDL_TAP"TRUE";
"B \NAC \NWC"10;
"S \NAC"
BN"0"60;
%"TAP"
"1","(-3475,2875)","0","mstr_standard","I233";
;
CDS_LIB"mstr_standard"
BODY_TYPE"PLUMBING"
HDL_TAP"TRUE";
"B \NAC \NWC"10;
"S \NAC"
BN"1"56;
%"TAP"
"1","(-3475,2975)","0","mstr_standard","I234";
;
CDS_LIB"mstr_standard"
BODY_TYPE"PLUMBING"
HDL_TAP"TRUE";
"B \NAC \NWC"10;
"S \NAC"
BN"2"52;
%"TAP"
"1","(-3275,2725)","0","mstr_standard","I235";
;
CDS_LIB"mstr_standard"
BODY_TYPE"PLUMBING"
HDL_TAP"TRUE";
"B \NAC \NWC"9;
"S \NAC"
BN"0"61;
%"SCONN288_DDR506112002KQ"
"2","(-4425,3725)","0","pure_quanta","I236";
;
LOCATION"J30"
$SEC"2"
CDS_SEC"2"
PART_TYPE"SMLF"
VALUE"SCONN288_DDR506112002KQ"
MATERIAL"IO"
PART_NUMBER"DFHST8FS479"
CDS_LMAN_SYM_OUTLINE"-600,1150,600,-1150"
NEEDS_NO_SIZE"TRUE"
CDS_LIB"pure_quanta";
"DQS7_A_C||TDQS7_A_C \B"
$PN"178"68;
"DQS6_A_T||TDQS6_A_T"
$PN"168"67;
"DQS8_B_T||TDQS8_B_T"
$PN"283"66;
"DQS8_B_C||TDQS8_B_C \B"
$PN"282"65;
"DQS7_B_T||TDQS7_B_T"
$PN"272"64;
"DQS0_A_C \B"
$PN"12"63;
"DQS0_A_T"
$PN"11"62;
"DQS0_B_C \B"
$PN"105"61;
"DQS0_B_T"
$PN"104"60;
"DQS1_A_C \B"
$PN"23"59;
"DQS1_A_T"
$PN"22"58;
"DQS1_B_C \B"
$PN"116"57;
"DQS1_B_T"
$PN"115"56;
"DQS2_A_C \B"
$PN"34"55;
"DQS2_A_T"
$PN"33"54;
"DQS2_B_C \B"
$PN"127"53;
"DQS2_B_T"
$PN"126"52;
"DQS3_A_C \B"
$PN"45"51;
"DQS3_A_T"
$PN"44"50;
"DQS3_B_C \B"
$PN"138"49;
"DQS3_B_T"
$PN"137"48;
"DQS4_A_C \B"
$PN"56"47;
"DQS4_A_T"
$PN"55"46;
"DQS4_B_C \B"
$PN"238"45;
"DQS4_B_T"
$PN"239"44;
"DQS5_A_C||TDQS5_A_C||DQS5_A_T||TDQS5_A_T \B"
$PN"156"43;
"DQS5_A_T||TDQS5_A_T"
$PN"157"42;
"DQS5_B_C||TDQS5_B_C \B"
$PN"249"41;
"DQS5_B_T||TDQS5_B_T"
$PN"250"40;
"DQS6_A_C||TDQS6_A_C||DQS6_A_T||TDQS6_A_T \B"
$PN"167"39;
"DQS6_B_C||TDQS6_B_C \B"
$PN"260"38;
"DQS6_B_T||TDQS6_B_T"
$PN"261"37;
"DQS7_A_T||TDQS7_A_T"
$PN"179"36;
"DQS7_B_C||TDQS7_B_C \B"
$PN"271"35;
"DQS8_A_C||TDQS8_A_C \B"
$PN"189"34;
"DQS8_A_T||TDQS8_A_T"
$PN"190"33;
"DQS9_A_C||TDQS9_A_C \B"
$PN"200"32;
"DQS9_A_T||TDQS9_A_T"
$PN"201"31;
"DQS9_B_C||TDQS9_B_C \B"
$PN"94"30;
"DQS9_B_T||TDQS9_B_T||DBI4_B_N"
$PN"93"29;
%"GND"
"1","(-2900,5450)","0","pure_quanta_power","I237";
;
CDS_LIB"pure_quanta_power"
BOM_COST"MEM"
SIZE"1B"
ROOM"MEM_EFGH_DECOUPLING_CAPS"
HDL_POWER"GND";
"A<SIZE-1..0>\NAC"26;
%"Q_CAP"
"1","(-2900,5800)","2","pure_quanta","I238";
;
LOCATION"C181"
$SEC"1"
CDS_SEC"1"
MATERIAL"X6S"
TOLERANCE"10%"
VALUE"10UF"
PART_NUMBER"CH6104KEA00"
VOLTAGE"25V"
PACK_TYPE"C0805"
BOM_COST"MEM"
CDS_LIB"pure_quanta"
ROOM"MEM_CH_A_CPU0_DIMM1";
"B"
$PN"2"26;
"A"
$PN"1"25;
%"Q_CAP"
"1","(-2325,5800)","2","pure_quanta","I239";
;
LOCATION"C182"
$SEC"1"
CDS_SEC"1"
MATERIAL"X6S"
TOLERANCE"10%"
VALUE"10UF"
VOLTAGE"25V"
PACK_TYPE"C0805"
PART_NUMBER"CH6104KEA00"
BOM_COST"MEM"
CDS_LIB"pure_quanta"
ROOM"MEM_CH_A_CPU0_DIMM1";
"B"
$PN"2"26;
"A"
$PN"1"25;
%"TAP"
"1","(-7800,4025)","2","mstr_standard","I24";
;
CDS_LIB"mstr_standard"
BODY_TYPE"PLUMBING"
HDL_TAP"TRUE";
"B \NAC \NWC"1;
"S \NAC"
BN"4"176;
%"UNIVERSAL_POWER"
"1","(-2900,6125)","0","pure_quanta_power","I240";
;
HDL_POWER"P12V_MEM_2"
CDS_LIB"pure_quanta_power";
"A"25;
%"Q_RES"
"1","(-7850,2875)","0","pure_quanta","I242";
;
$LOCATION"R1583"
CDS_LOCATION"R1583"
$SEC"1"
CDS_SEC"1"
VALUE"49.9"
CDS_LIB"pure_quanta"
MATERIAL"CHIP"
PACK_TYPE"0402LF"
WATTAGE"1/16W"
TOLERANCE"1%"
PART_NUMBER"CS04992FB07";
"B"
$PN"2"14;
"A"
$PN"1"15;
%"TAP"
"1","(-7800,4125)","2","mstr_standard","I25";
;
CDS_LIB"mstr_standard"
BODY_TYPE"PLUMBING"
HDL_TAP"TRUE";
"B \NAC \NWC"1;
"S \NAC"
BN"6"158;
%"TAP"
"1","(-7800,4075)","2","mstr_standard","I26";
;
CDS_LIB"mstr_standard"
BODY_TYPE"PLUMBING"
HDL_TAP"TRUE";
"B \NAC \NWC"1;
"S \NAC"
BN"5"157;
%"TAP"
"1","(-7800,4175)","2","mstr_standard","I27";
;
CDS_LIB"mstr_standard"
BODY_TYPE"PLUMBING"
HDL_TAP"TRUE";
"B \NAC \NWC"1;
"S \NAC"
BN"7"177;
%"TAP"
"1","(-7800,4875)","2","mstr_standard","I37";
;
CDS_LIB"mstr_standard"
BODY_TYPE"PLUMBING"
HDL_TAP"TRUE";
"B \NAC \NWC"3;
"S \NAC"
BN"0"171;
%"TAP"
"1","(-7800,4925)","2","mstr_standard","I38";
;
CDS_LIB"mstr_standard"
BODY_TYPE"PLUMBING"
HDL_TAP"TRUE";
"B \NAC \NWC"3;
"S \NAC"
BN"1"169;
%"TAP"
"1","(-7800,4975)","2","mstr_standard","I39";
;
CDS_LIB"mstr_standard"
BODY_TYPE"PLUMBING"
HDL_TAP"TRUE";
"B \NAC \NWC"3;
"S \NAC"
BN"2"167;
%"TAP"
"1","(-7800,5025)","2","mstr_standard","I40";
;
CDS_LIB"mstr_standard"
BODY_TYPE"PLUMBING"
HDL_TAP"TRUE";
"B \NAC \NWC"3;
"S \NAC"
BN"3"165;
%"TAP"
"1","(-7800,5075)","2","mstr_standard","I41";
;
CDS_LIB"mstr_standard"
BODY_TYPE"PLUMBING"
HDL_TAP"TRUE";
"B \NAC \NWC"3;
"S \NAC"
BN"4"163;
%"TAP"
"1","(-7800,5175)","2","mstr_standard","I42";
;
CDS_LIB"mstr_standard"
BODY_TYPE"PLUMBING"
HDL_TAP"TRUE";
"B \NAC \NWC"3;
"S \NAC"
BN"6"159;
%"TAP"
"1","(-7800,5125)","2","mstr_standard","I43";
;
CDS_LIB"mstr_standard"
BODY_TYPE"PLUMBING"
HDL_TAP"TRUE";
"B \NAC \NWC"3;
"S \NAC"
BN"5"161;
%"TAP"
"1","(-7800,5375)","2","mstr_standard","I45";
;
CDS_LIB"mstr_standard"
BODY_TYPE"PLUMBING"
HDL_TAP"TRUE";
"B \NAC \NWC"2;
"S \NAC"
BN"2"168;
%"TAP"
"1","(-7800,5425)","2","mstr_standard","I46";
;
CDS_LIB"mstr_standard"
BODY_TYPE"PLUMBING"
HDL_TAP"TRUE";
"B \NAC \NWC"2;
"S \NAC"
BN"3"166;
%"TAP"
"1","(-7800,5325)","2","mstr_standard","I47";
;
CDS_LIB"mstr_standard"
BODY_TYPE"PLUMBING"
HDL_TAP"TRUE";
"B \NAC \NWC"2;
"S \NAC"
BN"1"170;
%"TAP"
"1","(-7800,5275)","2","mstr_standard","I48";
;
CDS_LIB"mstr_standard"
BODY_TYPE"PLUMBING"
HDL_TAP"TRUE";
"B \NAC \NWC"2;
"S \NAC"
BN"0"172;
%"TAP"
"1","(-7800,5475)","2","mstr_standard","I49";
;
CDS_LIB"mstr_standard"
BODY_TYPE"PLUMBING"
HDL_TAP"TRUE";
"B \NAC \NWC"2;
"S \NAC"
BN"4"164;
%"TAP"
"1","(-7800,5575)","2","mstr_standard","I50";
;
CDS_LIB"mstr_standard"
BODY_TYPE"PLUMBING"
HDL_TAP"TRUE";
"B \NAC \NWC"2;
"S \NAC"
BN"6"160;
%"TAP"
"1","(-7800,5525)","2","mstr_standard","I51";
;
CDS_LIB"mstr_standard"
BODY_TYPE"PLUMBING"
HDL_TAP"TRUE";
"B \NAC \NWC"2;
"S \NAC"
BN"5"162;
%"SCONN288_DDR506112002KQ"
"1","(-6950,3825)","0","pure_quanta","I52";
;
LOCATION"J30"
$SEC"1"
CDS_SEC"1"
PART_TYPE"SMLF"
MATERIAL"IO"
PART_NUMBER"DFHST8FS479"
VALUE"SCONN288_DDR506112002KQ"
CDS_LMAN_SYM_OUTLINE"-450,1900,450,-1850"
NEEDS_NO_SIZE"TRUE"
CDS_LIB"pure_quanta";
"PWR_GOOD||FAIL_N"
$PN"147"16;
"DQ31_A"
$PN"194"69;
"CB7_A"
$PN"205"177;
"CB4_A"
$PN"58"176;
"CB1_A"
$PN"53"175;
"CB7_B"
$PN"236"174;
"ALERT_N \B"
$PN"62"173;
"CA0_A"
$PN"66"172;
"CA0_B"
$PN"76"171;
"CA1_A"
$PN"211"170;
"CA1_B"
$PN"221"169;
"CA2_A"
$PN"68"168;
"CA2_B"
$PN"78"167;
"CA3_A"
$PN"213"166;
"CA3_B"
$PN"223"165;
"CA4_A"
$PN"70"164;
"CA4_B"
$PN"80"163;
"CA5_A"
$PN"215"162;
"CA5_B"
$PN"225"161;
"CA6_A"
$PN"72"160;
"CA6_B"
$PN"82"159;
"CB6_A"
$PN"203"158;
"CB5_A"
$PN"60"157;
"CB3_A"
$PN"198"156;
"CB2_A"
$PN"196"155;
"CB0_A"
$PN"51"154;
"CB6_B"
$PN"234"153;
"CB5_B"
$PN"91"152;
"CB4_B"
$PN"89"151;
"CB3_B"
$PN"243"150;
"CB2_B"
$PN"241"149;
"CB1_B"
$PN"98"148;
"CB0_B"
$PN"96"147;
"CK_C \B"
$PN"218"146;
"CK_T"
$PN"217"145;
"CS0_A_N"
$PN"64"144;
"CS0_B_N"
$PN"84"143;
"CS1_A_N"
$PN"209"142;
"CS1_B_N"
$PN"229"141;
"DQ30_A"
$PN"192"140;
"DQ29_A"
$PN"49"139;
"DQ28_A"
$PN"47"138;
"DQ27_A"
$PN"187"137;
"DQ26_A"
$PN"185"136;
"DQ25_A"
$PN"42"135;
"DQ24_A"
$PN"40"134;
"DQ23_A"
$PN"183"133;
"DQ22_A"
$PN"181"132;
"DQ21_A"
$PN"38"131;
"DQ20_A"
$PN"36"130;
"DQ19_A"
$PN"176"129;
"DQ18_A"
$PN"174"128;
"DQ17_A"
$PN"31"127;
"DQ16_A"
$PN"29"126;
"DQ15_A"
$PN"172"125;
"DQ14_A"
$PN"170"124;
"DQ13_A"
$PN"27"123;
"DQ12_A"
$PN"25"122;
"DQ11_A"
$PN"165"121;
"DQ10_A"
$PN"163"120;
"DQ9_A"
$PN"20"119;
"DQ8_A"
$PN"18"118;
"DQ7_A"
$PN"161"117;
"DQ6_A"
$PN"159"116;
"DQ5_A"
$PN"16"115;
"DQ4_A"
$PN"14"114;
"DQ3_A"
$PN"154"113;
"DQ2_A"
$PN"152"112;
"DQ1_A"
$PN"9"111;
"DQ0_A"
$PN"7"110;
"DQ31_B"
$PN"287"109;
"DQ30_B"
$PN"285"108;
"DQ29_B"
$PN"142"107;
"DQ28_B"
$PN"140"106;
"DQ27_B"
$PN"280"105;
"DQ26_B"
$PN"278"104;
"DQ25_B"
$PN"135"103;
"DQ24_B"
$PN"133"102;
"DQ23_B"
$PN"276"101;
"DQ22_B"
$PN"274"100;
"DQ21_B"
$PN"131"99;
"DQ20_B"
$PN"129"98;
"DQ19_B"
$PN"269"97;
"DQ18_B"
$PN"267"96;
"DQ17_B"
$PN"124"95;
"DQ16_B"
$PN"122"94;
"DQ15_B"
$PN"265"93;
"DQ14_B"
$PN"263"92;
"DQ13_B"
$PN"120"91;
"DQ12_B"
$PN"118"90;
"DQ11_B"
$PN"258"89;
"DQ10_B"
$PN"256"88;
"DQ9_B"
$PN"113"87;
"DQ8_B"
$PN"111"86;
"DQ7_B"
$PN"254"85;
"DQ6_B"
$PN"252"84;
"DQ5_B"
$PN"109"83;
"DQ4_B"
$PN"107"82;
"DQ3_B"
$PN"247"81;
"DQ2_B"
$PN"245"80;
"DQ1_B"
$PN"102"79;
"DQ0_B"
$PN"100"78;
"HAS"
$PN"148"18;
"HSCL"
$PN"4"14;
"HSDA"
$PN"5"17;
"LBD||RSP_A_N"
$PN"86"77;
"LBS||RSP_B_N"
$PN"87"76;
"PAR_A"
$PN"74"75;
"PAR_B"
$PN"227"74;
"RESET_N \B"
$PN"207"73;
"RFU6"
$PN"232"23;
"RFU5"
$PN"231"72;
"RFU4"
$PN"220"71;
"RFU3"
$PN"150"22;
"RFU2"
$PN"149"70;
"RFU1"
$PN"144"21;
"RFU0"
$PN"2"20;
"VIN_MGMT"
$PN"3"19;
%"TAP"
"1","(-6100,2375)","0","mstr_standard","I53";
;
CDS_LIB"mstr_standard"
BODY_TYPE"PLUMBING"
HDL_TAP"TRUE";
"B \NAC \NWC"6;
"S \NAC"
BN"0"78;
%"TAP"
"1","(-6100,2425)","0","mstr_standard","I54";
;
CDS_LIB"mstr_standard"
BODY_TYPE"PLUMBING"
HDL_TAP"TRUE";
"B \NAC \NWC"6;
"S \NAC"
BN"1"79;
%"TAP"
"1","(-6100,2525)","0","mstr_standard","I55";
;
CDS_LIB"mstr_standard"
BODY_TYPE"PLUMBING"
HDL_TAP"TRUE";
"B \NAC \NWC"6;
"S \NAC"
BN"3"81;
%"TAP"
"1","(-6100,2475)","0","mstr_standard","I56";
;
CDS_LIB"mstr_standard"
BODY_TYPE"PLUMBING"
HDL_TAP"TRUE";
"B \NAC \NWC"6;
"S \NAC"
BN"2"80;
%"TAP"
"1","(-6100,2575)","0","mstr_standard","I57";
;
CDS_LIB"mstr_standard"
BODY_TYPE"PLUMBING"
HDL_TAP"TRUE";
"B \NAC \NWC"6;
"S \NAC"
BN"4"82;
%"TAP"
"1","(-6100,2625)","0","mstr_standard","I58";
;
CDS_LIB"mstr_standard"
BODY_TYPE"PLUMBING"
HDL_TAP"TRUE";
"B \NAC \NWC"6;
"S \NAC"
BN"5"83;
%"TAP"
"1","(-6100,2675)","0","mstr_standard","I59";
;
CDS_LIB"mstr_standard"
BODY_TYPE"PLUMBING"
HDL_TAP"TRUE";
"B \NAC \NWC"6;
"S \NAC"
BN"6"84;
%"TAP"
"1","(-6100,2775)","0","mstr_standard","I60";
;
CDS_LIB"mstr_standard"
BODY_TYPE"PLUMBING"
HDL_TAP"TRUE";
"B \NAC \NWC"6;
"S \NAC"
BN"8"86;
%"TAP"
"1","(-6100,2725)","0","mstr_standard","I61";
;
CDS_LIB"mstr_standard"
BODY_TYPE"PLUMBING"
HDL_TAP"TRUE";
"B \NAC \NWC"6;
"S \NAC"
BN"7"85;
%"TAP"
"1","(-6100,2825)","0","mstr_standard","I62";
;
CDS_LIB"mstr_standard"
BODY_TYPE"PLUMBING"
HDL_TAP"TRUE";
"B \NAC \NWC"6;
"S \NAC"
BN"9"87;
%"TAP"
"1","(-6100,2875)","0","mstr_standard","I63";
;
CDS_LIB"mstr_standard"
BODY_TYPE"PLUMBING"
HDL_TAP"TRUE";
"B \NAC \NWC"6;
"S \NAC"
BN"10"88;
%"TAP"
"1","(-6100,2925)","0","mstr_standard","I64";
;
CDS_LIB"mstr_standard"
BODY_TYPE"PLUMBING"
HDL_TAP"TRUE";
"B \NAC \NWC"6;
"S \NAC"
BN"11"89;
%"TAP"
"1","(-6100,2975)","0","mstr_standard","I65";
;
CDS_LIB"mstr_standard"
BODY_TYPE"PLUMBING"
HDL_TAP"TRUE";
"B \NAC \NWC"6;
"S \NAC"
BN"12"90;
%"TAP"
"1","(-6100,3025)","0","mstr_standard","I66";
;
CDS_LIB"mstr_standard"
BODY_TYPE"PLUMBING"
HDL_TAP"TRUE";
"B \NAC \NWC"6;
"S \NAC"
BN"13"91;
%"TAP"
"1","(-6100,3125)","0","mstr_standard","I67";
;
CDS_LIB"mstr_standard"
BODY_TYPE"PLUMBING"
HDL_TAP"TRUE";
"B \NAC \NWC"6;
"S \NAC"
BN"15"93;
%"TAP"
"1","(-6100,3075)","0","mstr_standard","I68";
;
CDS_LIB"mstr_standard"
BODY_TYPE"PLUMBING"
HDL_TAP"TRUE";
"B \NAC \NWC"6;
"S \NAC"
BN"14"92;
%"TAP"
"1","(-6100,3175)","0","mstr_standard","I69";
;
CDS_LIB"mstr_standard"
BODY_TYPE"PLUMBING"
HDL_TAP"TRUE";
"B \NAC \NWC"6;
"S \NAC"
BN"16"94;
%"VCC_CORE"
"1","(-8650,3600)","0","mstr_symbols","I7";
;
HDL_POWER"P3V3_STBY"
CDS_LIB"mstr_symbols"
VOLTAGE"3.3"
ROOM"PVCCINFAON_CPU1_CTRL";
"A"19;
%"TAP"
"1","(-6100,3225)","0","mstr_standard","I70";
;
CDS_LIB"mstr_standard"
BODY_TYPE"PLUMBING"
HDL_TAP"TRUE";
"B \NAC \NWC"6;
"S \NAC"
BN"17"95;
%"TAP"
"1","(-6100,3275)","0","mstr_standard","I71";
;
CDS_LIB"mstr_standard"
BODY_TYPE"PLUMBING"
HDL_TAP"TRUE";
"B \NAC \NWC"6;
"S \NAC"
BN"18"96;
%"TAP"
"1","(-6100,3325)","0","mstr_standard","I72";
;
CDS_LIB"mstr_standard"
BODY_TYPE"PLUMBING"
HDL_TAP"TRUE";
"B \NAC \NWC"6;
"S \NAC"
BN"19"97;
%"TAP"
"1","(-6100,3425)","0","mstr_standard","I73";
;
CDS_LIB"mstr_standard"
BODY_TYPE"PLUMBING"
HDL_TAP"TRUE";
"B \NAC \NWC"6;
"S \NAC"
BN"21"99;
%"TAP"
"1","(-6100,3375)","0","mstr_standard","I74";
;
CDS_LIB"mstr_standard"
BODY_TYPE"PLUMBING"
HDL_TAP"TRUE";
"B \NAC \NWC"6;
"S \NAC"
BN"20"98;
%"TAP"
"1","(-6100,3475)","0","mstr_standard","I75";
;
CDS_LIB"mstr_standard"
BODY_TYPE"PLUMBING"
HDL_TAP"TRUE";
"B \NAC \NWC"6;
"S \NAC"
BN"22"100;
%"TAP"
"1","(-6100,3525)","0","mstr_standard","I76";
;
CDS_LIB"mstr_standard"
BODY_TYPE"PLUMBING"
HDL_TAP"TRUE";
"B \NAC \NWC"6;
"S \NAC"
BN"23"101;
%"TAP"
"1","(-6100,3575)","0","mstr_standard","I77";
;
CDS_LIB"mstr_standard"
BODY_TYPE"PLUMBING"
HDL_TAP"TRUE";
"B \NAC \NWC"6;
"S \NAC"
BN"24"102;
%"TAP"
"1","(-6100,3675)","0","mstr_standard","I78";
;
CDS_LIB"mstr_standard"
BODY_TYPE"PLUMBING"
HDL_TAP"TRUE";
"B \NAC \NWC"6;
"S \NAC"
BN"26"104;
%"TAP"
"1","(-6100,3625)","0","mstr_standard","I79";
;
CDS_LIB"mstr_standard"
BODY_TYPE"PLUMBING"
HDL_TAP"TRUE";
"B \NAC \NWC"6;
"S \NAC"
BN"25"103;
%"TAP"
"1","(-6100,3725)","0","mstr_standard","I80";
;
CDS_LIB"mstr_standard"
BODY_TYPE"PLUMBING"
HDL_TAP"TRUE";
"B \NAC \NWC"6;
"S \NAC"
BN"27"105;
%"TAP"
"1","(-6100,3775)","0","mstr_standard","I81";
;
CDS_LIB"mstr_standard"
BODY_TYPE"PLUMBING"
HDL_TAP"TRUE";
"B \NAC \NWC"6;
"S \NAC"
BN"28"106;
%"TAP"
"1","(-6100,3875)","0","mstr_standard","I82";
;
CDS_LIB"mstr_standard"
BODY_TYPE"PLUMBING"
HDL_TAP"TRUE";
"B \NAC \NWC"6;
"S \NAC"
BN"30"108;
%"TAP"
"1","(-6100,3825)","0","mstr_standard","I83";
;
CDS_LIB"mstr_standard"
BODY_TYPE"PLUMBING"
HDL_TAP"TRUE";
"B \NAC \NWC"6;
"S \NAC"
BN"29"107;
%"TAP"
"1","(-6100,3925)","0","mstr_standard","I84";
;
CDS_LIB"mstr_standard"
BODY_TYPE"PLUMBING"
HDL_TAP"TRUE";
"B \NAC \NWC"6;
"S \NAC"
BN"31"109;
%"TAP"
"1","(-6100,4025)","0","mstr_standard","I85";
;
CDS_LIB"mstr_standard"
BODY_TYPE"PLUMBING"
HDL_TAP"TRUE";
"B \NAC \NWC"5;
"S \NAC"
BN"0"110;
%"TAP"
"1","(-6100,4125)","0","mstr_standard","I86";
;
CDS_LIB"mstr_standard"
BODY_TYPE"PLUMBING"
HDL_TAP"TRUE";
"B \NAC \NWC"5;
"S \NAC"
BN"2"112;
%"TAP"
"1","(-6100,4075)","0","mstr_standard","I87";
;
CDS_LIB"mstr_standard"
BODY_TYPE"PLUMBING"
HDL_TAP"TRUE";
"B \NAC \NWC"5;
"S \NAC"
BN"1"111;
%"TAP"
"1","(-6100,4175)","0","mstr_standard","I88";
;
CDS_LIB"mstr_standard"
BODY_TYPE"PLUMBING"
HDL_TAP"TRUE";
"B \NAC \NWC"5;
"S \NAC"
BN"3"113;
END.
